#ISCELL
  logical_power bom_note *
  *
#ISCELL
  logical_power cad_note *
  *
#ISCELL
  mstr_misc dns *
  *
#ISCELL
  pure_quanta quanta_title_block_c *
  *
#ISCELL
  standard offpage *
  page45_i1
#CELL
  pure_quanta q_res *
  page45_i19
#ISCELL
  standard offpage *
  page45_i2
#CELL
  pure_quanta q_res *
  page45_i20
#CELL
  pure_quanta q_res *
  page45_i21
#CELL
  pure_quanta q_res *
  page45_i22
#CELL
  pure_quanta q_res *
  page45_i23
#CELL
  pure_quanta q_res *
  page45_i24
#ISCELL
  standard offpage *
  page45_i3
#CELL
  pure_quanta q_res *
  page45_i33
#CELL
  pure_quanta q_res *
  page45_i34
#CELL
  pure_quanta q_res *
  page45_i35
#ISCELL
  standard offpage *
  page45_i4
#ISCELL
  logical_power universal_gnd *
  page45_i40
#CELL
  pure_quanta q_cap *
  page45_i42
#ISCELL
  logical_power universal_gnd *
  page45_i43
#ISCELL
  logical_power universal_gnd *
  page45_i44
#CELL
  pure_quanta q_cap *
  page45_i45
#ISCELL
  logical_power universal_power *
  page45_i46
#CELL
  pure_quanta q_res *
  page45_i48
#ISCELL
  logical_power universal_power *
  page45_i49
#ISCELL
  standard offpage *
  page45_i5
#CELL
  pure_quanta q_res *
  page45_i51
#ISCELL
  logical_power universal_gnd *
  page45_i52
#CELL
  pure_quanta sconn16_acaspi006p06 *
  page45_i53
#CELL
  pure_quanta mx25l51245gmi10g *
  page45_i54
#ISCELL
  logical_power universal_power *
  page45_i55
#ISCELL
  logical_power universal_gnd *
  page45_i56
#ISCELL
  standard offpage *
  page45_i6
